G04 ================== begin FILE IDENTIFICATION RECORD ==================*
G04 Layout Name:  15669-1.brd*
G04 Film Name:    DP_REF_L8*
G04 File Format:  Gerber RS274X*
G04 File Origin:  Cadence Allegro 16.5-S056*
G04 Origin Date:  Wed Nov 16 04:09:30 2016*
G04 *
G04 Layer:  BOARD GEOMETRY/DP_REF_L8_TBL*
G04 Layer:  BOARD GEOMETRY/DP_REF_L8_BOTTOM*
G04 Layer:  BOARD GEOMETRY/PANEL_OUTLINE*
G04 *
G04 Offset:    (0.00 0.00)*
G04 Mirror:    No*
G04 Mode:      Positive*
G04 Rotation:  0*
G04 FullContactRelief:  No*
G04 UndefLineWidth:     6.00*
G04 ================== end FILE IDENTIFICATION RECORD ====================*
%FSLAX35Y35*MOIN*%
%IR0*IPPOS*OFA0.00000B0.00000*MIA0B0*SFA1.00000B1.00000*%
%ADD10C,.02*%
%ADD11C,.006*%
%ADD12C,.00688*%
G75*
%LPD*%
G75*
G54D10*
G01X1178253Y1853826D02*
X1948253D01*
G01X1178253Y1957776D02*
Y1853826D01*
G01Y1923126D02*
X1948253D01*
G01X1178253Y1888476D02*
X1948253D01*
G01X1178253Y1957776D02*
X1948253D01*
G01X1353253D02*
Y1853826D01*
G01X1633253Y1957776D02*
Y1853826D01*
G01X1738253Y1957776D02*
Y1853826D01*
G01X1948253Y1957776D02*
Y1853826D01*
G54D11*
G01X-84302Y-32800D02*
Y-50300D01*
G01X-89324Y-32800D02*
X-79280D01*
G01X-70514Y-50300D02*
Y-32800D01*
G01Y-41258D02*
X-69422Y-39800D01*
X-68330Y-38925D01*
X-66584Y-38634D01*
X-65274Y-38925D01*
X-63745Y-40092D01*
X-63090Y-41842D01*
Y-50300D01*
G01X-49302Y-38634D02*
Y-50300D01*
G01Y-33967D02*
X-49739Y-33675D01*
Y-33092D01*
X-49302Y-32800D01*
X-48865Y-33092D01*
Y-33675D01*
X-49302Y-33967D01*
G01X-35077Y-48259D02*
X-33985Y-49425D01*
X-32457Y-50300D01*
X-31147D01*
X-29837Y-49717D01*
X-28964Y-48842D01*
X-28527Y-47676D01*
X-28745Y-45925D01*
X-29619Y-45050D01*
X-33549Y-43300D01*
X-34422Y-41258D01*
X-33985Y-39800D01*
X-33112Y-38925D01*
X-31802Y-38634D01*
X-30492Y-38925D01*
X-29182Y-39800D01*
G01X141Y-54675D02*
X1670Y-55842D01*
X3416Y-56133D01*
X4944Y-55842D01*
X6255Y-54384D01*
X7128Y-52342D01*
Y-38634D01*
G01Y-40967D02*
X6255Y-39800D01*
X4944Y-38925D01*
X3416Y-38634D01*
X1670Y-39217D01*
X578Y-40383D01*
X-296Y-42425D01*
X-732Y-44467D01*
X-514Y-46217D01*
X360Y-48259D01*
X1670Y-49717D01*
X3416Y-50300D01*
X4726Y-50008D01*
X6255Y-48842D01*
X7128Y-47676D01*
G01X17423Y-42425D02*
X24410D01*
X23755Y-40383D01*
X22663Y-39217D01*
X21135Y-38634D01*
X19606Y-38925D01*
X18296Y-39800D01*
X17423Y-41842D01*
X16986Y-43592D01*
Y-45342D01*
X17423Y-47092D01*
X18515Y-48842D01*
X19825Y-50008D01*
X21353Y-50300D01*
X22881Y-49717D01*
X24410Y-47967D01*
G01X35141Y-50300D02*
Y-38634D01*
G01Y-40967D02*
X36233Y-39800D01*
X37325Y-38925D01*
X38853Y-38634D01*
X39944Y-38925D01*
X41255Y-39800D01*
G01X51768Y-50300D02*
Y-32800D01*
G01Y-41550D02*
X52860Y-39800D01*
X54170Y-38925D01*
X55480Y-38634D01*
X57444Y-39217D01*
X58755Y-40383D01*
X59628Y-42425D01*
Y-44758D01*
X59191Y-47092D01*
X58318Y-48842D01*
X56790Y-50008D01*
X55480Y-50300D01*
X54170Y-50008D01*
X52860Y-49134D01*
X51768Y-47676D01*
G01X69923Y-42425D02*
X76910D01*
X76255Y-40383D01*
X75163Y-39217D01*
X73635Y-38634D01*
X72106Y-38925D01*
X70796Y-39800D01*
X69923Y-41842D01*
X69486Y-43592D01*
Y-45342D01*
X69923Y-47092D01*
X71015Y-48842D01*
X72325Y-50008D01*
X73853Y-50300D01*
X75381Y-49717D01*
X76910Y-47967D01*
G01X87641Y-50300D02*
Y-38634D01*
G01Y-40967D02*
X88733Y-39800D01*
X89825Y-38925D01*
X91353Y-38634D01*
X92444Y-38925D01*
X93755Y-39800D01*
G01X125698Y-38634D02*
Y-50300D01*
G01Y-33967D02*
X125261Y-33675D01*
Y-33092D01*
X125698Y-32800D01*
X126135Y-33092D01*
Y-33675D01*
X125698Y-33967D01*
G01X139923Y-48259D02*
X141015Y-49425D01*
X142543Y-50300D01*
X143853D01*
X145163Y-49717D01*
X146036Y-48842D01*
X146473Y-47676D01*
X146255Y-45925D01*
X145381Y-45050D01*
X141451Y-43300D01*
X140578Y-41258D01*
X141015Y-39800D01*
X141888Y-38925D01*
X143198Y-38634D01*
X144508Y-38925D01*
X145818Y-39800D01*
G01X174704Y-54675D02*
X176233Y-55842D01*
X177543Y-56133D01*
X179290Y-55550D01*
X180600Y-54092D01*
X181255Y-51466D01*
Y-38634D01*
G01Y-33967D02*
X180818Y-33675D01*
Y-33092D01*
X181255Y-32800D01*
X181691Y-33092D01*
Y-33675D01*
X181255Y-33967D01*
G01X191986Y-38634D02*
Y-46800D01*
X192860Y-48842D01*
X194170Y-50008D01*
X195698Y-50300D01*
X197226Y-50008D01*
X198536Y-48842D01*
X199410Y-46800D01*
G01Y-50300D02*
Y-38634D01*
G01X209923Y-48259D02*
X211015Y-49425D01*
X212543Y-50300D01*
X213853D01*
X215163Y-49717D01*
X216036Y-48842D01*
X216473Y-47676D01*
X216255Y-45925D01*
X215381Y-45050D01*
X211451Y-43300D01*
X210578Y-41258D01*
X211015Y-39800D01*
X211888Y-38925D01*
X213198Y-38634D01*
X214508Y-38925D01*
X215818Y-39800D01*
G01X230698Y-32800D02*
Y-50300D01*
G01X227641Y-38634D02*
X233755D01*
G01X264388Y-50300D02*
Y-35425D01*
X264825Y-33967D01*
X265698Y-33092D01*
X267008Y-32800D01*
X268318Y-33383D01*
X268973Y-34842D01*
G01X266353Y-39800D02*
X261986D01*
G01X283198Y-50300D02*
X281888Y-50008D01*
X280578Y-48842D01*
X279704Y-46800D01*
X279268Y-44467D01*
X279704Y-42133D01*
X280578Y-40092D01*
X281888Y-38925D01*
X283198Y-38634D01*
X284508Y-38925D01*
X285818Y-40092D01*
X286691Y-42133D01*
X286910Y-44467D01*
X286691Y-46800D01*
X285818Y-48842D01*
X284508Y-50008D01*
X283198Y-50300D01*
G01X297641D02*
Y-38634D01*
G01Y-40967D02*
X298733Y-39800D01*
X299825Y-38925D01*
X301353Y-38634D01*
X302444Y-38925D01*
X303755Y-39800D01*
G01X331113Y-55550D02*
X332423Y-56133D01*
X334170Y-55550D01*
X335261Y-54384D01*
X336135Y-52925D01*
X337444Y-48259D01*
X340283Y-38634D01*
G01X333296D02*
X337444Y-48259D01*
G01X353198Y-50300D02*
X351888Y-50008D01*
X350578Y-48842D01*
X349704Y-46800D01*
X349268Y-44467D01*
X349704Y-42133D01*
X350578Y-40092D01*
X351888Y-38925D01*
X353198Y-38634D01*
X354508Y-38925D01*
X355818Y-40092D01*
X356691Y-42133D01*
X356910Y-44467D01*
X356691Y-46800D01*
X355818Y-48842D01*
X354508Y-50008D01*
X353198Y-50300D01*
G01X366986Y-38634D02*
Y-46800D01*
X367860Y-48842D01*
X369170Y-50008D01*
X370698Y-50300D01*
X372226Y-50008D01*
X373536Y-48842D01*
X374410Y-46800D01*
G01Y-50300D02*
Y-38634D01*
G01X385141Y-50300D02*
Y-38634D01*
G01Y-40967D02*
X386233Y-39800D01*
X387325Y-38925D01*
X388853Y-38634D01*
X389944Y-38925D01*
X391255Y-39800D01*
G01X420141Y-50300D02*
Y-38634D01*
G01Y-40967D02*
X421233Y-39800D01*
X422325Y-38925D01*
X423853Y-38634D01*
X424944Y-38925D01*
X426255Y-39800D01*
G01X437423Y-42425D02*
X444410D01*
X443755Y-40383D01*
X442663Y-39217D01*
X441135Y-38634D01*
X439606Y-38925D01*
X438296Y-39800D01*
X437423Y-41842D01*
X436986Y-43592D01*
Y-45342D01*
X437423Y-47092D01*
X438515Y-48842D01*
X439825Y-50008D01*
X441353Y-50300D01*
X442881Y-49717D01*
X444410Y-47967D01*
G01X456888Y-50300D02*
Y-35425D01*
X457325Y-33967D01*
X458198Y-33092D01*
X459508Y-32800D01*
X460818Y-33383D01*
X461473Y-34842D01*
G01X458853Y-39800D02*
X454486D01*
G01X472423Y-42425D02*
X479410D01*
X478755Y-40383D01*
X477663Y-39217D01*
X476135Y-38634D01*
X474606Y-38925D01*
X473296Y-39800D01*
X472423Y-41842D01*
X471986Y-43592D01*
Y-45342D01*
X472423Y-47092D01*
X473515Y-48842D01*
X474825Y-50008D01*
X476353Y-50300D01*
X477881Y-49717D01*
X479410Y-47967D01*
G01X490141Y-50300D02*
Y-38634D01*
G01Y-40967D02*
X491233Y-39800D01*
X492325Y-38925D01*
X493853Y-38634D01*
X494944Y-38925D01*
X496255Y-39800D01*
G01X507423Y-42425D02*
X514410D01*
X513755Y-40383D01*
X512663Y-39217D01*
X511135Y-38634D01*
X509606Y-38925D01*
X508296Y-39800D01*
X507423Y-41842D01*
X506986Y-43592D01*
Y-45342D01*
X507423Y-47092D01*
X508515Y-48842D01*
X509825Y-50008D01*
X511353Y-50300D01*
X512881Y-49717D01*
X514410Y-47967D01*
G01X524486Y-50300D02*
Y-38634D01*
G01Y-41550D02*
X525360Y-40092D01*
X526670Y-38925D01*
X528416Y-38634D01*
X529944Y-38925D01*
X531255Y-40092D01*
X531910Y-42133D01*
Y-50300D01*
G01X549191Y-40092D02*
X547663Y-38925D01*
X546353Y-38634D01*
X544606Y-39217D01*
X543296Y-40383D01*
X542423Y-42425D01*
X542204Y-44467D01*
X542423Y-46509D01*
X543296Y-48259D01*
X544606Y-49717D01*
X546353Y-50300D01*
X547881Y-49717D01*
X549191Y-48550D01*
G01X559923Y-42425D02*
X566910D01*
X566255Y-40383D01*
X565163Y-39217D01*
X563635Y-38634D01*
X562106Y-38925D01*
X560796Y-39800D01*
X559923Y-41842D01*
X559486Y-43592D01*
Y-45342D01*
X559923Y-47092D01*
X561015Y-48842D01*
X562325Y-50008D01*
X563853Y-50300D01*
X565381Y-49717D01*
X566910Y-47967D01*
G01X598198Y-32800D02*
Y-50300D01*
G01X595141Y-38634D02*
X601255D01*
G01X615698Y-50300D02*
X614388Y-50008D01*
X613078Y-48842D01*
X612204Y-46800D01*
X611768Y-44467D01*
X612204Y-42133D01*
X613078Y-40092D01*
X614388Y-38925D01*
X615698Y-38634D01*
X617008Y-38925D01*
X618318Y-40092D01*
X619191Y-42133D01*
X619410Y-44467D01*
X619191Y-46800D01*
X618318Y-48842D01*
X617008Y-50008D01*
X615698Y-50300D01*
G01X649388D02*
Y-35425D01*
X649825Y-33967D01*
X650698Y-33092D01*
X652008Y-32800D01*
X653318Y-33383D01*
X653973Y-34842D01*
G01X651353Y-39800D02*
X646986D01*
G01X668198Y-38634D02*
Y-50300D01*
G01Y-33967D02*
X667761Y-33675D01*
Y-33092D01*
X668198Y-32800D01*
X668635Y-33092D01*
Y-33675D01*
X668198Y-33967D01*
G01X681986Y-50300D02*
Y-38634D01*
G01Y-41550D02*
X682860Y-40092D01*
X684170Y-38925D01*
X685916Y-38634D01*
X687444Y-38925D01*
X688755Y-40092D01*
X689410Y-42133D01*
Y-50300D01*
G01X707128Y-32800D02*
Y-50300D01*
G01Y-47676D02*
X706255Y-49134D01*
X704944Y-50008D01*
X703416Y-50300D01*
X701670Y-49717D01*
X700360Y-48259D01*
X699486Y-46509D01*
X699268Y-44467D01*
X699486Y-42425D01*
X700360Y-40675D01*
X701670Y-39217D01*
X703416Y-38634D01*
X704944Y-38925D01*
X706036Y-39509D01*
X707128Y-40675D01*
G01X738198Y-32800D02*
Y-50300D01*
G01X735141Y-38634D02*
X741255D01*
G01X751986Y-50300D02*
Y-32800D01*
G01Y-41258D02*
X753078Y-39800D01*
X754170Y-38925D01*
X755916Y-38634D01*
X757226Y-38925D01*
X758755Y-40092D01*
X759410Y-41842D01*
Y-50300D01*
G01X769923Y-42425D02*
X776910D01*
X776255Y-40383D01*
X775163Y-39217D01*
X773635Y-38634D01*
X772106Y-38925D01*
X770796Y-39800D01*
X769923Y-41842D01*
X769486Y-43592D01*
Y-45342D01*
X769923Y-47092D01*
X771015Y-48842D01*
X772325Y-50008D01*
X773853Y-50300D01*
X775381Y-49717D01*
X776910Y-47967D01*
G01X803395Y-50300D02*
Y-32800D01*
X807761D01*
X809508Y-33675D01*
X810818Y-34842D01*
X811910Y-36591D01*
X812783Y-38634D01*
X813001Y-41550D01*
X812783Y-44467D01*
X811910Y-46509D01*
X810818Y-48259D01*
X809508Y-49425D01*
X807761Y-50300D01*
X803395D01*
G01X821331D02*
Y-32800D01*
X826571D01*
X828318Y-33675D01*
X829628Y-35717D01*
X830065Y-38050D01*
X829628Y-40383D01*
X828536Y-42133D01*
X826571Y-43009D01*
X821331D01*
G01X860698Y-38634D02*
Y-50300D01*
G01Y-33967D02*
X860261Y-33675D01*
Y-33092D01*
X860698Y-32800D01*
X861135Y-33092D01*
Y-33675D01*
X860698Y-33967D01*
G01X871648Y-50300D02*
Y-38634D01*
G01Y-41842D02*
X872303Y-40383D01*
X873395Y-39217D01*
X874923Y-38634D01*
X876451Y-39217D01*
X877543Y-40383D01*
X878198Y-41842D01*
Y-50300D01*
G01Y-41842D02*
X878853Y-40383D01*
X879944Y-39217D01*
X881473Y-38634D01*
X883001Y-39217D01*
X884093Y-40383D01*
X884748Y-42133D01*
Y-50300D01*
G01X891768Y-56133D02*
Y-38634D01*
G01Y-41258D02*
X892860Y-39800D01*
X893951Y-38925D01*
X895698Y-38634D01*
X897226Y-38925D01*
X898755Y-40383D01*
X899410Y-42425D01*
X899628Y-44467D01*
X899410Y-46509D01*
X898755Y-48550D01*
X897444Y-49717D01*
X895698Y-50300D01*
X894170Y-50008D01*
X892641Y-49134D01*
X891768Y-47967D01*
G01X909923Y-42425D02*
X916910D01*
X916255Y-40383D01*
X915163Y-39217D01*
X913635Y-38634D01*
X912106Y-38925D01*
X910796Y-39800D01*
X909923Y-41842D01*
X909486Y-43592D01*
Y-45342D01*
X909923Y-47092D01*
X911015Y-48842D01*
X912325Y-50008D01*
X913853Y-50300D01*
X915381Y-49717D01*
X916910Y-47967D01*
G01X934628Y-32800D02*
Y-50300D01*
G01Y-47676D02*
X933755Y-49134D01*
X932444Y-50008D01*
X930916Y-50300D01*
X929170Y-49717D01*
X927860Y-48259D01*
X926986Y-46509D01*
X926768Y-44467D01*
X926986Y-42425D01*
X927860Y-40675D01*
X929170Y-39217D01*
X930916Y-38634D01*
X932444Y-38925D01*
X933536Y-39509D01*
X934628Y-40675D01*
G01X952128Y-50300D02*
Y-38634D01*
G01Y-40675D02*
X951255Y-39509D01*
X949944Y-38925D01*
X948416Y-38634D01*
X946888Y-39217D01*
X945578Y-40383D01*
X944704Y-42133D01*
X944268Y-44467D01*
X944704Y-46800D01*
X945578Y-48550D01*
X946888Y-49717D01*
X948416Y-50300D01*
X949944Y-50008D01*
X951255Y-49134D01*
X952128Y-47967D01*
G01X961986Y-50300D02*
Y-38634D01*
G01Y-41550D02*
X962860Y-40092D01*
X964170Y-38925D01*
X965916Y-38634D01*
X967444Y-38925D01*
X968755Y-40092D01*
X969410Y-42133D01*
Y-50300D01*
G01X986691Y-40092D02*
X985163Y-38925D01*
X983853Y-38634D01*
X982106Y-39217D01*
X980796Y-40383D01*
X979923Y-42425D01*
X979704Y-44467D01*
X979923Y-46509D01*
X980796Y-48259D01*
X982106Y-49717D01*
X983853Y-50300D01*
X985381Y-49717D01*
X986691Y-48550D01*
G01X997423Y-42425D02*
X1004410D01*
X1003755Y-40383D01*
X1002663Y-39217D01*
X1001135Y-38634D01*
X999606Y-38925D01*
X998296Y-39800D01*
X997423Y-41842D01*
X996986Y-43592D01*
Y-45342D01*
X997423Y-47092D01*
X998515Y-48842D01*
X999825Y-50008D01*
X1001353Y-50300D01*
X1002881Y-49717D01*
X1004410Y-47967D01*
G01X1035698Y-32800D02*
Y-50300D01*
G01X1032641Y-38634D02*
X1038755D01*
G01X1050141Y-50300D02*
Y-38634D01*
G01Y-40967D02*
X1051233Y-39800D01*
X1052325Y-38925D01*
X1053853Y-38634D01*
X1054944Y-38925D01*
X1056255Y-39800D01*
G01X1074628Y-50300D02*
Y-38634D01*
G01Y-40675D02*
X1073755Y-39509D01*
X1072444Y-38925D01*
X1070916Y-38634D01*
X1069388Y-39217D01*
X1068078Y-40383D01*
X1067204Y-42133D01*
X1066768Y-44467D01*
X1067204Y-46800D01*
X1068078Y-48550D01*
X1069388Y-49717D01*
X1070916Y-50300D01*
X1072444Y-50008D01*
X1073755Y-49134D01*
X1074628Y-47967D01*
G01X1091691Y-40092D02*
X1090163Y-38925D01*
X1088853Y-38634D01*
X1087106Y-39217D01*
X1085796Y-40383D01*
X1084923Y-42425D01*
X1084704Y-44467D01*
X1084923Y-46509D01*
X1085796Y-48259D01*
X1087106Y-49717D01*
X1088853Y-50300D01*
X1090381Y-49717D01*
X1091691Y-48550D01*
G01X1102423Y-42425D02*
X1109410D01*
X1108755Y-40383D01*
X1107663Y-39217D01*
X1106135Y-38634D01*
X1104606Y-38925D01*
X1103296Y-39800D01*
X1102423Y-41842D01*
X1101986Y-43592D01*
Y-45342D01*
X1102423Y-47092D01*
X1103515Y-48842D01*
X1104825Y-50008D01*
X1106353Y-50300D01*
X1107881Y-49717D01*
X1109410Y-47967D01*
G01X1119923Y-48259D02*
X1121015Y-49425D01*
X1122543Y-50300D01*
X1123853D01*
X1125163Y-49717D01*
X1126036Y-48842D01*
X1126473Y-47676D01*
X1126255Y-45925D01*
X1125381Y-45050D01*
X1121451Y-43300D01*
X1120578Y-41258D01*
X1121015Y-39800D01*
X1121888Y-38925D01*
X1123198Y-38634D01*
X1124508Y-38925D01*
X1125818Y-39800D01*
G01X1158198Y-38634D02*
Y-50300D01*
G01Y-33967D02*
X1157761Y-33675D01*
Y-33092D01*
X1158198Y-32800D01*
X1158635Y-33092D01*
Y-33675D01*
X1158198Y-33967D01*
G01X1171986Y-50300D02*
Y-38634D01*
G01Y-41550D02*
X1172860Y-40092D01*
X1174170Y-38925D01*
X1175916Y-38634D01*
X1177444Y-38925D01*
X1178755Y-40092D01*
X1179410Y-42133D01*
Y-50300D01*
G01X1210698D02*
Y-32800D01*
G01X1232128Y-50300D02*
Y-38634D01*
G01Y-40675D02*
X1231255Y-39509D01*
X1229944Y-38925D01*
X1228416Y-38634D01*
X1226888Y-39217D01*
X1225578Y-40383D01*
X1224704Y-42133D01*
X1224268Y-44467D01*
X1224704Y-46800D01*
X1225578Y-48550D01*
X1226888Y-49717D01*
X1228416Y-50300D01*
X1229944Y-50008D01*
X1231255Y-49134D01*
X1232128Y-47967D01*
G01X1241113Y-55550D02*
X1242423Y-56133D01*
X1244170Y-55550D01*
X1245261Y-54384D01*
X1246135Y-52925D01*
X1247444Y-48259D01*
X1250283Y-38634D01*
G01X1243296D02*
X1247444Y-48259D01*
G01X1259923Y-42425D02*
X1266910D01*
X1266255Y-40383D01*
X1265163Y-39217D01*
X1263635Y-38634D01*
X1262106Y-38925D01*
X1260796Y-39800D01*
X1259923Y-41842D01*
X1259486Y-43592D01*
Y-45342D01*
X1259923Y-47092D01*
X1261015Y-48842D01*
X1262325Y-50008D01*
X1263853Y-50300D01*
X1265381Y-49717D01*
X1266910Y-47967D01*
G01X1277641Y-50300D02*
Y-38634D01*
G01Y-40967D02*
X1278733Y-39800D01*
X1279825Y-38925D01*
X1281353Y-38634D01*
X1282444Y-38925D01*
X1283755Y-39800D01*
G01X1311331Y-32800D02*
Y-50300D01*
X1320065D01*
G01X1333198D02*
X1334726Y-50008D01*
X1336473Y-49134D01*
X1337565Y-47676D01*
X1338001Y-45633D01*
X1337565Y-43592D01*
X1336255Y-41842D01*
X1334290Y-40967D01*
X1332106D01*
X1330796Y-40383D01*
X1329704Y-38925D01*
X1329268Y-36884D01*
X1329923Y-34842D01*
X1331451Y-33383D01*
X1333198Y-32800D01*
X1334944Y-33383D01*
X1336473Y-34842D01*
X1337128Y-36884D01*
X1336691Y-38925D01*
X1335600Y-40383D01*
X1334290Y-40967D01*
X1332106D01*
X1330141Y-41842D01*
X1328831Y-43592D01*
X1328395Y-45633D01*
X1328831Y-47676D01*
X1329923Y-49134D01*
X1331670Y-50008D01*
X1333198Y-50300D01*
G01X1350698Y-50883D02*
X1350261Y-50592D01*
Y-50008D01*
X1350698Y-49717D01*
X1351135Y-50008D01*
Y-50592D01*
X1350698Y-50883D01*
G01X1201883Y1950376D02*
X1207123D01*
G01X1204503D02*
Y1932876D01*
G01X1201883D02*
X1207123D01*
G01X1216326D02*
Y1950376D01*
X1222003Y1935793D01*
X1227680Y1950376D01*
Y1932876D01*
G01X1235136D02*
Y1950376D01*
X1240376D01*
X1242123Y1949501D01*
X1243433Y1947459D01*
X1243870Y1945126D01*
X1243433Y1942793D01*
X1242341Y1941043D01*
X1240376Y1940167D01*
X1235136D01*
G01X1255911Y1927043D02*
X1253728Y1929959D01*
X1252636Y1932876D01*
Y1944542D01*
X1253728Y1947459D01*
X1255911Y1950376D01*
G01X1274503Y1932876D02*
X1272756Y1933168D01*
X1271228Y1934334D01*
X1269918Y1936084D01*
X1269044Y1938126D01*
X1268608Y1940459D01*
Y1942793D01*
X1269044Y1945126D01*
X1269918Y1947168D01*
X1271228Y1948917D01*
X1272756Y1950084D01*
X1274503Y1950376D01*
X1276249Y1950084D01*
X1277778Y1948917D01*
X1279088Y1947168D01*
X1279962Y1945126D01*
X1280398Y1942793D01*
Y1940459D01*
X1279962Y1938126D01*
X1279088Y1936084D01*
X1277778Y1934334D01*
X1276249Y1933168D01*
X1274503Y1932876D01*
G01X1288291D02*
Y1950376D01*
G01Y1941918D02*
X1289383Y1943376D01*
X1290475Y1944251D01*
X1292221Y1944542D01*
X1293531Y1944251D01*
X1295060Y1943084D01*
X1295715Y1941334D01*
Y1932876D01*
G01X1302953D02*
Y1944542D01*
G01Y1941334D02*
X1303608Y1942793D01*
X1304700Y1943959D01*
X1306228Y1944542D01*
X1307756Y1943959D01*
X1308848Y1942793D01*
X1309503Y1941334D01*
Y1932876D01*
G01Y1941334D02*
X1310158Y1942793D01*
X1311249Y1943959D01*
X1312778Y1944542D01*
X1314306Y1943959D01*
X1315398Y1942793D01*
X1316053Y1941043D01*
Y1932876D01*
G01X1328095Y1927043D02*
X1330278Y1929959D01*
X1331370Y1932876D01*
Y1944542D01*
X1330278Y1947459D01*
X1328095Y1950376D01*
G01X1180000Y1967526D02*
Y1985026D01*
X1184366D01*
X1186113Y1984151D01*
X1187423Y1982984D01*
X1188515Y1981235D01*
X1189388Y1979192D01*
X1189606Y1976276D01*
X1189388Y1973359D01*
X1188515Y1971317D01*
X1187423Y1969567D01*
X1186113Y1968401D01*
X1184366Y1967526D01*
X1180000D01*
G01X1197936D02*
Y1985026D01*
X1203176D01*
X1204923Y1984151D01*
X1206233Y1982109D01*
X1206670Y1979776D01*
X1206233Y1977443D01*
X1205141Y1975693D01*
X1203176Y1974817D01*
X1197936D01*
G01X1234683Y1985026D02*
X1239923D01*
G01X1237303D02*
Y1967526D01*
G01X1234683D02*
X1239923D01*
G01X1249126D02*
Y1985026D01*
X1254803Y1970443D01*
X1260480Y1985026D01*
Y1967526D01*
G01X1267936D02*
Y1985026D01*
X1273176D01*
X1274923Y1984151D01*
X1276233Y1982109D01*
X1276670Y1979776D01*
X1276233Y1977443D01*
X1275141Y1975693D01*
X1273176Y1974817D01*
X1267936D01*
G01X1294170Y1967526D02*
X1285436D01*
Y1985026D01*
X1294170D01*
G01X1290676Y1976568D02*
X1285436D01*
G01X1302500Y1967526D02*
Y1985026D01*
X1306866D01*
X1308613Y1984151D01*
X1309923Y1982984D01*
X1311015Y1981235D01*
X1311888Y1979192D01*
X1312106Y1976276D01*
X1311888Y1973359D01*
X1311015Y1971317D01*
X1309923Y1969567D01*
X1308613Y1968401D01*
X1306866Y1967526D01*
X1302500D01*
G01X1319344D02*
X1324803Y1985026D01*
X1330262Y1967526D01*
G01X1328296Y1973651D02*
X1321309D01*
G01X1337281Y1967526D02*
Y1985026D01*
X1347325Y1967526D01*
Y1985026D01*
G01X1364606Y1983567D02*
X1363296Y1984443D01*
X1361768Y1985026D01*
X1360021D01*
X1358056Y1984151D01*
X1356528Y1982693D01*
X1355436Y1980942D01*
X1354563Y1978026D01*
X1354344Y1975401D01*
X1354781Y1972776D01*
X1355436Y1971026D01*
X1356746Y1969276D01*
X1358275Y1968109D01*
X1359803Y1967526D01*
X1361331D01*
X1362860Y1968109D01*
X1364170Y1968984D01*
X1365262Y1970150D01*
G01X1381670Y1967526D02*
X1372936D01*
Y1985026D01*
X1381670D01*
G01X1378176Y1976568D02*
X1372936D01*
G01X1412303Y1985026D02*
Y1967526D01*
G01X1407281Y1985026D02*
X1417325D01*
G01X1424344Y1967526D02*
X1429803Y1985026D01*
X1435262Y1967526D01*
G01X1433296Y1973651D02*
X1426309D01*
G01X1449049Y1976859D02*
X1449923Y1977734D01*
X1450578Y1979192D01*
X1451015Y1981235D01*
X1450578Y1982984D01*
X1449705Y1984151D01*
X1448176Y1985026D01*
X1442281D01*
Y1967526D01*
X1449486D01*
X1451015Y1968692D01*
X1451888Y1970443D01*
X1452325Y1972484D01*
X1451888Y1974526D01*
X1450578Y1976276D01*
X1449049Y1976859D01*
X1442281D01*
G01X1460436Y1985026D02*
Y1967526D01*
X1469170D01*
G01X1486670D02*
X1477936D01*
Y1985026D01*
X1486670D01*
G01X1483176Y1976568D02*
X1477936D01*
G01X1499803Y1966943D02*
X1499366Y1967234D01*
Y1967818D01*
X1499803Y1968109D01*
X1500240Y1967818D01*
Y1967234D01*
X1499803Y1966943D01*
G01Y1974817D02*
X1499366Y1975109D01*
Y1975693D01*
X1499803Y1975984D01*
X1500240Y1975693D01*
Y1975109D01*
X1499803Y1974817D01*
G01X1530436Y1985026D02*
Y1967526D01*
X1539170D01*
G01X1552303D02*
X1553831Y1967818D01*
X1555578Y1968692D01*
X1556670Y1970150D01*
X1557106Y1972193D01*
X1556670Y1974234D01*
X1555360Y1975984D01*
X1553395Y1976859D01*
X1551211D01*
X1549901Y1977443D01*
X1548809Y1978901D01*
X1548373Y1980942D01*
X1549028Y1982984D01*
X1550556Y1984443D01*
X1552303Y1985026D01*
X1554049Y1984443D01*
X1555578Y1982984D01*
X1556233Y1980942D01*
X1555796Y1978901D01*
X1554705Y1977443D01*
X1553395Y1976859D01*
X1551211D01*
X1549246Y1975984D01*
X1547936Y1974234D01*
X1547500Y1972193D01*
X1547936Y1970150D01*
X1549028Y1968692D01*
X1550775Y1967818D01*
X1552303Y1967526D01*
G01X1217200Y1862993D02*
X1226806Y1875826D01*
G01X1222003Y1878159D02*
Y1860659D01*
G01X1226806Y1862993D02*
X1217200Y1875826D01*
G01X1215453Y1869409D02*
X1228553D01*
G01X1239503Y1863576D02*
Y1881076D01*
X1236883Y1877576D01*
G01Y1863576D02*
X1242123D01*
G01X1257003Y1881076D02*
X1255256Y1880493D01*
X1253946Y1879034D01*
X1253073Y1877285D01*
X1252418Y1874951D01*
X1252200Y1872326D01*
X1252418Y1869701D01*
X1253073Y1867367D01*
X1253946Y1865617D01*
X1255256Y1864159D01*
X1257003Y1863576D01*
X1258749Y1864159D01*
X1260060Y1865617D01*
X1260933Y1867367D01*
X1261588Y1869701D01*
X1261806Y1872326D01*
X1261588Y1874951D01*
X1260933Y1877285D01*
X1260060Y1879034D01*
X1258749Y1880493D01*
X1257003Y1881076D01*
G01X1274503D02*
X1272756Y1880493D01*
X1271446Y1879034D01*
X1270573Y1877285D01*
X1269918Y1874951D01*
X1269700Y1872326D01*
X1269918Y1869701D01*
X1270573Y1867367D01*
X1271446Y1865617D01*
X1272756Y1864159D01*
X1274503Y1863576D01*
X1276249Y1864159D01*
X1277560Y1865617D01*
X1278433Y1867367D01*
X1279088Y1869701D01*
X1279306Y1872326D01*
X1279088Y1874951D01*
X1278433Y1877285D01*
X1277560Y1879034D01*
X1276249Y1880493D01*
X1274503Y1881076D01*
G01X1292003Y1862993D02*
X1291566Y1863284D01*
Y1863868D01*
X1292003Y1864159D01*
X1292440Y1863868D01*
Y1863284D01*
X1292003Y1862993D01*
G01X1309503Y1881076D02*
X1307756Y1880493D01*
X1306446Y1879034D01*
X1305573Y1877285D01*
X1304918Y1874951D01*
X1304700Y1872326D01*
X1304918Y1869701D01*
X1305573Y1867367D01*
X1306446Y1865617D01*
X1307756Y1864159D01*
X1309503Y1863576D01*
X1311249Y1864159D01*
X1312560Y1865617D01*
X1313433Y1867367D01*
X1314088Y1869701D01*
X1314306Y1872326D01*
X1314088Y1874951D01*
X1313433Y1877285D01*
X1312560Y1879034D01*
X1311249Y1880493D01*
X1309503Y1881076D01*
G01X1239503Y1898226D02*
X1241031Y1898518D01*
X1242778Y1899392D01*
X1243870Y1900850D01*
X1244306Y1902893D01*
X1243870Y1904934D01*
X1242560Y1906684D01*
X1240595Y1907559D01*
X1238411D01*
X1237101Y1908143D01*
X1236009Y1909601D01*
X1235573Y1911642D01*
X1236228Y1913684D01*
X1237756Y1915143D01*
X1239503Y1915726D01*
X1241249Y1915143D01*
X1242778Y1913684D01*
X1243433Y1911642D01*
X1242996Y1909601D01*
X1241905Y1908143D01*
X1240595Y1907559D01*
X1238411D01*
X1236446Y1906684D01*
X1235136Y1904934D01*
X1234700Y1902893D01*
X1235136Y1900850D01*
X1236228Y1899392D01*
X1237975Y1898518D01*
X1239503Y1898226D01*
G01X1252200Y1900850D02*
X1253509Y1899392D01*
X1255038Y1898518D01*
X1257003Y1898226D01*
X1258968Y1898809D01*
X1260496Y1899976D01*
X1261588Y1902017D01*
X1261806Y1904351D01*
X1261370Y1906684D01*
X1260278Y1908143D01*
X1258749Y1909309D01*
X1257221Y1909601D01*
X1255693Y1909309D01*
X1253728Y1908143D01*
X1254383Y1915726D01*
X1260278D01*
G01X1274503Y1897643D02*
X1274066Y1897934D01*
Y1898518D01*
X1274503Y1898809D01*
X1274940Y1898518D01*
Y1897934D01*
X1274503Y1897643D01*
G01X1292003Y1915726D02*
X1290256Y1915143D01*
X1288946Y1913684D01*
X1288073Y1911935D01*
X1287418Y1909601D01*
X1287200Y1906976D01*
X1287418Y1904351D01*
X1288073Y1902017D01*
X1288946Y1900267D01*
X1290256Y1898809D01*
X1292003Y1898226D01*
X1293749Y1898809D01*
X1295060Y1900267D01*
X1295933Y1902017D01*
X1296588Y1904351D01*
X1296806Y1906976D01*
X1296588Y1909601D01*
X1295933Y1911935D01*
X1295060Y1913684D01*
X1293749Y1915143D01*
X1292003Y1915726D01*
G01X1399203Y1950376D02*
X1402259Y1932876D01*
X1405753Y1950376D01*
X1409246Y1932876D01*
X1412303Y1950376D01*
G01X1420633D02*
X1425873D01*
G01X1423253D02*
Y1932876D01*
G01X1420633D02*
X1425873D01*
G01X1435950D02*
Y1950376D01*
X1440316D01*
X1442063Y1949501D01*
X1443373Y1948334D01*
X1444465Y1946585D01*
X1445338Y1944542D01*
X1445556Y1941626D01*
X1445338Y1938709D01*
X1444465Y1936667D01*
X1443373Y1934917D01*
X1442063Y1933751D01*
X1440316Y1932876D01*
X1435950D01*
G01X1458253Y1950376D02*
Y1932876D01*
G01X1453231Y1950376D02*
X1463275D01*
G01X1471168Y1932876D02*
Y1950376D01*
G01X1480338D02*
Y1932876D01*
G01Y1941626D02*
X1471168D01*
G01X1492161Y1927043D02*
X1489978Y1929959D01*
X1488886Y1932876D01*
Y1944542D01*
X1489978Y1947459D01*
X1492161Y1950376D01*
G01X1504203Y1932876D02*
Y1944542D01*
G01Y1941334D02*
X1504858Y1942793D01*
X1505950Y1943959D01*
X1507478Y1944542D01*
X1509006Y1943959D01*
X1510098Y1942793D01*
X1510753Y1941334D01*
Y1932876D01*
G01Y1941334D02*
X1511408Y1942793D01*
X1512499Y1943959D01*
X1514028Y1944542D01*
X1515556Y1943959D01*
X1516648Y1942793D01*
X1517303Y1941043D01*
Y1932876D01*
G01X1528253Y1944542D02*
Y1932876D01*
G01Y1949209D02*
X1527816Y1949501D01*
Y1950084D01*
X1528253Y1950376D01*
X1528690Y1950084D01*
Y1949501D01*
X1528253Y1949209D01*
G01X1545753Y1932876D02*
Y1950376D01*
G01X1559978Y1934917D02*
X1561070Y1933751D01*
X1562598Y1932876D01*
X1563908D01*
X1565218Y1933459D01*
X1566091Y1934334D01*
X1566528Y1935500D01*
X1566310Y1937251D01*
X1565436Y1938126D01*
X1561506Y1939876D01*
X1560633Y1941918D01*
X1561070Y1943376D01*
X1561943Y1944251D01*
X1563253Y1944542D01*
X1564563Y1944251D01*
X1565873Y1943376D01*
G01X1581845Y1927043D02*
X1584028Y1929959D01*
X1585120Y1932876D01*
Y1944542D01*
X1584028Y1947459D01*
X1581845Y1950376D01*
G01X1419105Y1905517D02*
X1420633Y1907559D01*
X1421943Y1908726D01*
X1423690Y1909309D01*
X1425218Y1908726D01*
X1426310Y1907559D01*
X1427183Y1905809D01*
X1427401Y1903768D01*
X1427183Y1902017D01*
X1426310Y1900267D01*
X1424999Y1898809D01*
X1423471Y1898226D01*
X1421725Y1898809D01*
X1420196Y1900559D01*
X1419323Y1903184D01*
X1419105Y1906101D01*
X1419541Y1909892D01*
X1420196Y1911935D01*
X1421288Y1913976D01*
X1422816Y1915434D01*
X1424345Y1915726D01*
X1425873Y1915143D01*
X1426965Y1913684D01*
G01X1440753Y1897643D02*
X1440316Y1897934D01*
Y1898518D01*
X1440753Y1898809D01*
X1441190Y1898518D01*
Y1897934D01*
X1440753Y1897643D01*
G01X1458253Y1898226D02*
X1459781Y1898518D01*
X1461528Y1899392D01*
X1462620Y1900850D01*
X1463056Y1902893D01*
X1462620Y1904934D01*
X1461310Y1906684D01*
X1459345Y1907559D01*
X1457161D01*
X1455851Y1908143D01*
X1454759Y1909601D01*
X1454323Y1911642D01*
X1454978Y1913684D01*
X1456506Y1915143D01*
X1458253Y1915726D01*
X1459999Y1915143D01*
X1461528Y1913684D01*
X1462183Y1911642D01*
X1461746Y1909601D01*
X1460655Y1908143D01*
X1459345Y1907559D01*
X1457161D01*
X1455196Y1906684D01*
X1453886Y1904934D01*
X1453450Y1902893D01*
X1453886Y1900850D01*
X1454978Y1899392D01*
X1456725Y1898518D01*
X1458253Y1898226D01*
G01X1475753D02*
X1477281Y1898518D01*
X1479028Y1899392D01*
X1480120Y1900850D01*
X1480556Y1902893D01*
X1480120Y1904934D01*
X1478810Y1906684D01*
X1476845Y1907559D01*
X1474661D01*
X1473351Y1908143D01*
X1472259Y1909601D01*
X1471823Y1911642D01*
X1472478Y1913684D01*
X1474006Y1915143D01*
X1475753Y1915726D01*
X1477499Y1915143D01*
X1479028Y1913684D01*
X1479683Y1911642D01*
X1479246Y1909601D01*
X1478155Y1908143D01*
X1476845Y1907559D01*
X1474661D01*
X1472696Y1906684D01*
X1471386Y1904934D01*
X1470950Y1902893D01*
X1471386Y1900850D01*
X1472478Y1899392D01*
X1474225Y1898518D01*
X1475753Y1898226D01*
G01X1489323Y1897643D02*
X1497183Y1915726D01*
G01X1505950Y1900850D02*
X1507259Y1899392D01*
X1508788Y1898518D01*
X1510753Y1898226D01*
X1512718Y1898809D01*
X1514246Y1899976D01*
X1515338Y1902017D01*
X1515556Y1904351D01*
X1515120Y1906684D01*
X1514028Y1908143D01*
X1512499Y1909309D01*
X1510971Y1909601D01*
X1509443Y1909309D01*
X1507478Y1908143D01*
X1508133Y1915726D01*
X1514028D01*
G01X1528253Y1897643D02*
X1527816Y1897934D01*
Y1898518D01*
X1528253Y1898809D01*
X1528690Y1898518D01*
Y1897934D01*
X1528253Y1897643D01*
G01X1545753Y1898226D02*
Y1915726D01*
X1543133Y1912226D01*
G01Y1898226D02*
X1548373D01*
G01X1558450Y1901726D02*
X1559759Y1899684D01*
X1561506Y1898518D01*
X1563471Y1898226D01*
X1565218Y1898518D01*
X1566965Y1899976D01*
X1568056Y1901726D01*
X1568275Y1903476D01*
X1567838Y1905517D01*
X1566310Y1906976D01*
X1564781Y1907559D01*
X1562816D01*
G01X1564781D02*
X1566091Y1908434D01*
X1567183Y1909892D01*
X1567620Y1911642D01*
X1567183Y1913393D01*
X1566091Y1914851D01*
X1564126Y1915726D01*
X1562161Y1915434D01*
X1560196Y1914267D01*
G01X1435950Y1866200D02*
X1437259Y1864742D01*
X1438788Y1863868D01*
X1440753Y1863576D01*
X1442718Y1864159D01*
X1444246Y1865326D01*
X1445338Y1867367D01*
X1445556Y1869701D01*
X1445120Y1872034D01*
X1444028Y1873493D01*
X1442499Y1874659D01*
X1440971Y1874951D01*
X1439443Y1874659D01*
X1437478Y1873493D01*
X1438133Y1881076D01*
X1444028D01*
G01X1458253Y1862993D02*
X1457816Y1863284D01*
Y1863868D01*
X1458253Y1864159D01*
X1458690Y1863868D01*
Y1863284D01*
X1458253Y1862993D01*
G01X1475753Y1881076D02*
X1474006Y1880493D01*
X1472696Y1879034D01*
X1471823Y1877285D01*
X1471168Y1874951D01*
X1470950Y1872326D01*
X1471168Y1869701D01*
X1471823Y1867367D01*
X1472696Y1865617D01*
X1474006Y1864159D01*
X1475753Y1863576D01*
X1477499Y1864159D01*
X1478810Y1865617D01*
X1479683Y1867367D01*
X1480338Y1869701D01*
X1480556Y1872326D01*
X1480338Y1874951D01*
X1479683Y1877285D01*
X1478810Y1879034D01*
X1477499Y1880493D01*
X1475753Y1881076D01*
G01X1489323Y1862993D02*
X1497183Y1881076D01*
G01X1506605Y1870867D02*
X1508133Y1872909D01*
X1509443Y1874076D01*
X1511190Y1874659D01*
X1512718Y1874076D01*
X1513810Y1872909D01*
X1514683Y1871159D01*
X1514901Y1869118D01*
X1514683Y1867367D01*
X1513810Y1865617D01*
X1512499Y1864159D01*
X1510971Y1863576D01*
X1509225Y1864159D01*
X1507696Y1865909D01*
X1506823Y1868534D01*
X1506605Y1871451D01*
X1507041Y1875242D01*
X1507696Y1877285D01*
X1508788Y1879326D01*
X1510316Y1880784D01*
X1511845Y1881076D01*
X1513373Y1880493D01*
X1514465Y1879034D01*
G01X1528253Y1862993D02*
X1527816Y1863284D01*
Y1863868D01*
X1528253Y1864159D01*
X1528690Y1863868D01*
Y1863284D01*
X1528253Y1862993D01*
G01X1545753Y1881076D02*
X1544006Y1880493D01*
X1542696Y1879034D01*
X1541823Y1877285D01*
X1541168Y1874951D01*
X1540950Y1872326D01*
X1541168Y1869701D01*
X1541823Y1867367D01*
X1542696Y1865617D01*
X1544006Y1864159D01*
X1545753Y1863576D01*
X1547499Y1864159D01*
X1548810Y1865617D01*
X1549683Y1867367D01*
X1550338Y1869701D01*
X1550556Y1872326D01*
X1550338Y1874951D01*
X1549683Y1877285D01*
X1548810Y1879034D01*
X1547499Y1880493D01*
X1545753Y1881076D01*
G01X1672200Y1863576D02*
Y1881076D01*
X1676566D01*
X1678313Y1880201D01*
X1679623Y1879034D01*
X1680715Y1877285D01*
X1681588Y1875242D01*
X1681806Y1872326D01*
X1681588Y1869409D01*
X1680715Y1867367D01*
X1679623Y1865617D01*
X1678313Y1864451D01*
X1676566Y1863576D01*
X1672200D01*
G01X1690136D02*
Y1881076D01*
X1695376D01*
X1697123Y1880201D01*
X1698433Y1878159D01*
X1698870Y1875826D01*
X1698433Y1873493D01*
X1697341Y1871743D01*
X1695376Y1870867D01*
X1690136D01*
G01X1659503Y1950376D02*
Y1932876D01*
G01X1654481Y1950376D02*
X1664525D01*
G01X1677003Y1932876D02*
Y1940751D01*
X1672636Y1950376D01*
G01X1681370D02*
X1677003Y1940751D01*
G01X1690136Y1932876D02*
Y1950376D01*
X1695376D01*
X1697123Y1949501D01*
X1698433Y1947459D01*
X1698870Y1945126D01*
X1698433Y1942793D01*
X1697341Y1941043D01*
X1695376Y1940167D01*
X1690136D01*
G01X1716370Y1932876D02*
X1707636D01*
Y1950376D01*
X1716370D01*
G01X1712876Y1941918D02*
X1707636D01*
G01X1672200Y1898226D02*
Y1915726D01*
X1676566D01*
X1678313Y1914851D01*
X1679623Y1913684D01*
X1680715Y1911935D01*
X1681588Y1909892D01*
X1681806Y1906976D01*
X1681588Y1904059D01*
X1680715Y1902017D01*
X1679623Y1900267D01*
X1678313Y1899101D01*
X1676566Y1898226D01*
X1672200D01*
G01X1690136D02*
Y1915726D01*
X1695376D01*
X1697123Y1914851D01*
X1698433Y1912809D01*
X1698870Y1910476D01*
X1698433Y1908143D01*
X1697341Y1906393D01*
X1695376Y1905517D01*
X1690136D01*
G01X1760136Y1932876D02*
Y1950376D01*
X1765595D01*
X1767341Y1949501D01*
X1768433Y1948334D01*
X1768870Y1946001D01*
X1768433Y1943667D01*
X1767123Y1942209D01*
X1765595Y1941334D01*
X1760136D01*
G01X1765595D02*
X1768870Y1932876D01*
G01X1778728Y1940751D02*
X1785715D01*
X1785060Y1942793D01*
X1783968Y1943959D01*
X1782440Y1944542D01*
X1780911Y1944251D01*
X1779601Y1943376D01*
X1778728Y1941334D01*
X1778291Y1939584D01*
Y1937834D01*
X1778728Y1936084D01*
X1779820Y1934334D01*
X1781130Y1933168D01*
X1782658Y1932876D01*
X1784186Y1933459D01*
X1785715Y1935209D01*
G01X1798193Y1932876D02*
Y1947751D01*
X1798630Y1949209D01*
X1799503Y1950084D01*
X1800813Y1950376D01*
X1802123Y1949793D01*
X1802778Y1948334D01*
G01X1800158Y1943376D02*
X1795791D01*
G01X1817003Y1932293D02*
X1816566Y1932584D01*
Y1933168D01*
X1817003Y1933459D01*
X1817440Y1933168D01*
Y1932584D01*
X1817003Y1932293D01*
G01X1847636Y1932876D02*
Y1950376D01*
X1852876D01*
X1854623Y1949501D01*
X1855933Y1947459D01*
X1856370Y1945126D01*
X1855933Y1942793D01*
X1854841Y1941043D01*
X1852876Y1940167D01*
X1847636D01*
G01X1869503Y1932876D02*
Y1950376D01*
G01X1890933Y1932876D02*
Y1944542D01*
G01Y1942501D02*
X1890060Y1943667D01*
X1888749Y1944251D01*
X1887221Y1944542D01*
X1885693Y1943959D01*
X1884383Y1942793D01*
X1883509Y1941043D01*
X1883073Y1938709D01*
X1883509Y1936376D01*
X1884383Y1934626D01*
X1885693Y1933459D01*
X1887221Y1932876D01*
X1888749Y1933168D01*
X1890060Y1934042D01*
X1890933Y1935209D01*
G01X1900791Y1932876D02*
Y1944542D01*
G01Y1941626D02*
X1901665Y1943084D01*
X1902975Y1944251D01*
X1904721Y1944542D01*
X1906249Y1944251D01*
X1907560Y1943084D01*
X1908215Y1941043D01*
Y1932876D01*
G01X1918728Y1940751D02*
X1925715D01*
X1925060Y1942793D01*
X1923968Y1943959D01*
X1922440Y1944542D01*
X1920911Y1944251D01*
X1919601Y1943376D01*
X1918728Y1941334D01*
X1918291Y1939584D01*
Y1937834D01*
X1918728Y1936084D01*
X1919820Y1934334D01*
X1921130Y1933168D01*
X1922658Y1932876D01*
X1924186Y1933459D01*
X1925715Y1935209D01*
G01X1830136Y1881076D02*
Y1863576D01*
X1838870D01*
G01X1851566D02*
X1852003Y1867367D01*
X1852658Y1870576D01*
X1853531Y1873493D01*
X1854623Y1876701D01*
X1856370Y1881076D01*
X1847636D01*
G01X1830136Y1915726D02*
Y1898226D01*
X1838870D01*
G01X1851566D02*
X1852003Y1902017D01*
X1852658Y1905226D01*
X1853531Y1908143D01*
X1854623Y1911351D01*
X1856370Y1915726D01*
X1847636D01*
G01X1965000Y1932293D02*
X1974606Y1945126D01*
G01X1969803Y1947459D02*
Y1929959D01*
G01X1974606Y1932293D02*
X1965000Y1945126D01*
G01X1963253Y1938709D02*
X1976353D01*
G01X2001965D02*
X2007641D01*
G01X2035000Y1932876D02*
Y1950376D01*
X2039366D01*
X2041113Y1949501D01*
X2042423Y1948334D01*
X2043515Y1946585D01*
X2044388Y1944542D01*
X2044606Y1941626D01*
X2044388Y1938709D01*
X2043515Y1936667D01*
X2042423Y1934917D01*
X2041113Y1933751D01*
X2039366Y1932876D01*
X2035000D01*
G01X2054028Y1940751D02*
X2061015D01*
X2060360Y1942793D01*
X2059268Y1943959D01*
X2057740Y1944542D01*
X2056211Y1944251D01*
X2054901Y1943376D01*
X2054028Y1941334D01*
X2053591Y1939584D01*
Y1937834D01*
X2054028Y1936084D01*
X2055120Y1934334D01*
X2056430Y1933168D01*
X2057958Y1932876D01*
X2059486Y1933459D01*
X2061015Y1935209D01*
G01X2071091Y1932876D02*
Y1944542D01*
G01Y1941626D02*
X2071965Y1943084D01*
X2073275Y1944251D01*
X2075021Y1944542D01*
X2076549Y1944251D01*
X2077860Y1943084D01*
X2078515Y1941043D01*
Y1932876D01*
G01X2092303D02*
X2090993Y1933168D01*
X2089683Y1934334D01*
X2088809Y1936376D01*
X2088373Y1938709D01*
X2088809Y1941043D01*
X2089683Y1943084D01*
X2090993Y1944251D01*
X2092303Y1944542D01*
X2093613Y1944251D01*
X2094923Y1943084D01*
X2095796Y1941043D01*
X2096015Y1938709D01*
X2095796Y1936376D01*
X2094923Y1934334D01*
X2093613Y1933168D01*
X2092303Y1932876D01*
G01X2109803Y1950376D02*
Y1932876D01*
G01X2106746Y1944542D02*
X2112860D01*
G01X2124028Y1940751D02*
X2131015D01*
X2130360Y1942793D01*
X2129268Y1943959D01*
X2127740Y1944542D01*
X2126211Y1944251D01*
X2124901Y1943376D01*
X2124028Y1941334D01*
X2123591Y1939584D01*
Y1937834D01*
X2124028Y1936084D01*
X2125120Y1934334D01*
X2126430Y1933168D01*
X2127958Y1932876D01*
X2129486Y1933459D01*
X2131015Y1935209D01*
G01X2141528Y1934917D02*
X2142620Y1933751D01*
X2144148Y1932876D01*
X2145458D01*
X2146768Y1933459D01*
X2147641Y1934334D01*
X2148078Y1935500D01*
X2147860Y1937251D01*
X2146986Y1938126D01*
X2143056Y1939876D01*
X2142183Y1941918D01*
X2142620Y1943376D01*
X2143493Y1944251D01*
X2144803Y1944542D01*
X2146113Y1944251D01*
X2147423Y1943376D01*
G01X2179803Y1950376D02*
Y1932876D01*
G01X2176746Y1944542D02*
X2182860D01*
G01X2193591Y1932876D02*
Y1950376D01*
G01Y1941918D02*
X2194683Y1943376D01*
X2195775Y1944251D01*
X2197521Y1944542D01*
X2198831Y1944251D01*
X2200360Y1943084D01*
X2201015Y1941334D01*
Y1932876D01*
G01X2218733D02*
Y1944542D01*
G01Y1942501D02*
X2217860Y1943667D01*
X2216549Y1944251D01*
X2215021Y1944542D01*
X2213493Y1943959D01*
X2212183Y1942793D01*
X2211309Y1941043D01*
X2210873Y1938709D01*
X2211309Y1936376D01*
X2212183Y1934626D01*
X2213493Y1933459D01*
X2215021Y1932876D01*
X2216549Y1933168D01*
X2217860Y1934042D01*
X2218733Y1935209D01*
G01X2232303Y1950376D02*
Y1932876D01*
G01X2229246Y1944542D02*
X2235360D01*
G01X2267303Y1950376D02*
Y1932876D01*
G01X2264246Y1944542D02*
X2270360D01*
G01X2281091Y1932876D02*
Y1950376D01*
G01Y1941918D02*
X2282183Y1943376D01*
X2283275Y1944251D01*
X2285021Y1944542D01*
X2286331Y1944251D01*
X2287860Y1943084D01*
X2288515Y1941334D01*
Y1932876D01*
G01X2302303Y1944542D02*
Y1932876D01*
G01Y1949209D02*
X2301866Y1949501D01*
Y1950084D01*
X2302303Y1950376D01*
X2302740Y1950084D01*
Y1949501D01*
X2302303Y1949209D01*
G01X2316528Y1934917D02*
X2317620Y1933751D01*
X2319148Y1932876D01*
X2320458D01*
X2321768Y1933459D01*
X2322641Y1934334D01*
X2323078Y1935500D01*
X2322860Y1937251D01*
X2321986Y1938126D01*
X2318056Y1939876D01*
X2317183Y1941918D01*
X2317620Y1943376D01*
X2318493Y1944251D01*
X2319803Y1944542D01*
X2321113Y1944251D01*
X2322423Y1943376D01*
G01X2352183Y1950376D02*
X2357423D01*
G01X2354803D02*
Y1932876D01*
G01X2352183D02*
X2357423D01*
G01X2365753D02*
Y1944542D01*
G01Y1941334D02*
X2366408Y1942793D01*
X2367500Y1943959D01*
X2369028Y1944542D01*
X2370556Y1943959D01*
X2371648Y1942793D01*
X2372303Y1941334D01*
Y1932876D01*
G01Y1941334D02*
X2372958Y1942793D01*
X2374049Y1943959D01*
X2375578Y1944542D01*
X2377106Y1943959D01*
X2378198Y1942793D01*
X2378853Y1941043D01*
Y1932876D01*
G01X2385873Y1927043D02*
Y1944542D01*
G01Y1941918D02*
X2386965Y1943376D01*
X2388056Y1944251D01*
X2389803Y1944542D01*
X2391331Y1944251D01*
X2392860Y1942793D01*
X2393515Y1940751D01*
X2393733Y1938709D01*
X2393515Y1936667D01*
X2392860Y1934626D01*
X2391549Y1933459D01*
X2389803Y1932876D01*
X2388275Y1933168D01*
X2386746Y1934042D01*
X2385873Y1935209D01*
G01X2404028Y1940751D02*
X2411015D01*
X2410360Y1942793D01*
X2409268Y1943959D01*
X2407740Y1944542D01*
X2406211Y1944251D01*
X2404901Y1943376D01*
X2404028Y1941334D01*
X2403591Y1939584D01*
Y1937834D01*
X2404028Y1936084D01*
X2405120Y1934334D01*
X2406430Y1933168D01*
X2407958Y1932876D01*
X2409486Y1933459D01*
X2411015Y1935209D01*
G01X2428733Y1950376D02*
Y1932876D01*
G01Y1935500D02*
X2427860Y1934042D01*
X2426549Y1933168D01*
X2425021Y1932876D01*
X2423275Y1933459D01*
X2421965Y1934917D01*
X2421091Y1936667D01*
X2420873Y1938709D01*
X2421091Y1940751D01*
X2421965Y1942501D01*
X2423275Y1943959D01*
X2425021Y1944542D01*
X2426549Y1944251D01*
X2427641Y1943667D01*
X2428733Y1942501D01*
G01X2446233Y1932876D02*
Y1944542D01*
G01Y1942501D02*
X2445360Y1943667D01*
X2444049Y1944251D01*
X2442521Y1944542D01*
X2440993Y1943959D01*
X2439683Y1942793D01*
X2438809Y1941043D01*
X2438373Y1938709D01*
X2438809Y1936376D01*
X2439683Y1934626D01*
X2440993Y1933459D01*
X2442521Y1932876D01*
X2444049Y1933168D01*
X2445360Y1934042D01*
X2446233Y1935209D01*
G01X2456091Y1932876D02*
Y1944542D01*
G01Y1941626D02*
X2456965Y1943084D01*
X2458275Y1944251D01*
X2460021Y1944542D01*
X2461549Y1944251D01*
X2462860Y1943084D01*
X2463515Y1941043D01*
Y1932876D01*
G01X2480796Y1943084D02*
X2479268Y1944251D01*
X2477958Y1944542D01*
X2476211Y1943959D01*
X2474901Y1942793D01*
X2474028Y1940751D01*
X2473809Y1938709D01*
X2474028Y1936667D01*
X2474901Y1934917D01*
X2476211Y1933459D01*
X2477958Y1932876D01*
X2479486Y1933459D01*
X2480796Y1934626D01*
G01X2491528Y1940751D02*
X2498515D01*
X2497860Y1942793D01*
X2496768Y1943959D01*
X2495240Y1944542D01*
X2493711Y1944251D01*
X2492401Y1943376D01*
X2491528Y1941334D01*
X2491091Y1939584D01*
Y1937834D01*
X2491528Y1936084D01*
X2492620Y1934334D01*
X2493930Y1933168D01*
X2495458Y1932876D01*
X2496986Y1933459D01*
X2498515Y1935209D01*
G01X2039803Y1909892D02*
Y1898226D01*
G01Y1914559D02*
X2039366Y1914851D01*
Y1915434D01*
X2039803Y1915726D01*
X2040240Y1915434D01*
Y1914851D01*
X2039803Y1914559D01*
G01X2054028Y1900267D02*
X2055120Y1899101D01*
X2056648Y1898226D01*
X2057958D01*
X2059268Y1898809D01*
X2060141Y1899684D01*
X2060578Y1900850D01*
X2060360Y1902601D01*
X2059486Y1903476D01*
X2055556Y1905226D01*
X2054683Y1907268D01*
X2055120Y1908726D01*
X2055993Y1909601D01*
X2057303Y1909892D01*
X2058613Y1909601D01*
X2059923Y1908726D01*
G01X2087281Y1898226D02*
Y1915726D01*
X2097325Y1898226D01*
Y1915726D01*
G01X2109803Y1898226D02*
X2108056Y1898518D01*
X2106528Y1899684D01*
X2105218Y1901434D01*
X2104344Y1903476D01*
X2103908Y1905809D01*
Y1908143D01*
X2104344Y1910476D01*
X2105218Y1912518D01*
X2106528Y1914267D01*
X2108056Y1915434D01*
X2109803Y1915726D01*
X2111549Y1915434D01*
X2113078Y1914267D01*
X2114388Y1912518D01*
X2115262Y1910476D01*
X2115698Y1908143D01*
Y1905809D01*
X2115262Y1903476D01*
X2114388Y1901434D01*
X2113078Y1899684D01*
X2111549Y1898518D01*
X2109803Y1898226D01*
G01X2127303Y1915726D02*
Y1898226D01*
G01X2122281Y1915726D02*
X2132325D01*
G01X2158591Y1909892D02*
Y1901726D01*
X2159465Y1899684D01*
X2160775Y1898518D01*
X2162303Y1898226D01*
X2163831Y1898518D01*
X2165141Y1899684D01*
X2166015Y1901726D01*
G01Y1898226D02*
Y1909892D01*
G01X2176528Y1900267D02*
X2177620Y1899101D01*
X2179148Y1898226D01*
X2180458D01*
X2181768Y1898809D01*
X2182641Y1899684D01*
X2183078Y1900850D01*
X2182860Y1902601D01*
X2181986Y1903476D01*
X2178056Y1905226D01*
X2177183Y1907268D01*
X2177620Y1908726D01*
X2178493Y1909601D01*
X2179803Y1909892D01*
X2181113Y1909601D01*
X2182423Y1908726D01*
G01X2194028Y1906101D02*
X2201015D01*
X2200360Y1908143D01*
X2199268Y1909309D01*
X2197740Y1909892D01*
X2196211Y1909601D01*
X2194901Y1908726D01*
X2194028Y1906684D01*
X2193591Y1904934D01*
Y1903184D01*
X2194028Y1901434D01*
X2195120Y1899684D01*
X2196430Y1898518D01*
X2197958Y1898226D01*
X2199486Y1898809D01*
X2201015Y1900559D01*
G01X2218733Y1915726D02*
Y1898226D01*
G01Y1900850D02*
X2217860Y1899392D01*
X2216549Y1898518D01*
X2215021Y1898226D01*
X2213275Y1898809D01*
X2211965Y1900267D01*
X2211091Y1902017D01*
X2210873Y1904059D01*
X2211091Y1906101D01*
X2211965Y1907851D01*
X2213275Y1909309D01*
X2215021Y1909892D01*
X2216549Y1909601D01*
X2217641Y1909017D01*
X2218733Y1907851D01*
G01X-7874Y0D02*
X-75552D01*
G02X-90552Y15000I0J15000D01*
G01Y519024D01*
G02X-75552Y534024I15000J0D01*
G01X-7874D01*
G01Y1030087D02*
X-75552D01*
G03X-90552Y1015087I0J-15000D01*
G01Y1001780D01*
G03X-75552Y986780I15000J0D01*
G01X-7874D01*
G01Y1992126D02*
X-75552D01*
G03X-90552Y1977126I0J-15000D01*
G01Y1915165D01*
G03X-75552Y1900165I15000J0D01*
G01X-7874D01*
G01X1023228Y1618051D02*
Y1675945D01*
G02X1028701Y1681417I5472J0D01*
G01X1033465D01*
X1037402Y1685354D01*
Y1988189D01*
G03X1033465Y1992126I-3937J0D01*
G01X3937D01*
G03X0Y1988189I0J-3937D01*
G01Y1661189D01*
X1969Y1659220D01*
X17323D01*
G02Y1650559I0J-4331D01*
G01X1969D01*
X0Y1648591D01*
Y1243866D01*
X1969Y1241898D01*
X17323D01*
G02Y1233236I0J-4331D01*
G01X1969D01*
X0Y1231268D01*
Y747803D01*
X1969Y745835D01*
X17323D01*
G02Y737173I0J-4331D01*
G01X1969D01*
X0Y735205D01*
Y3937D01*
G03X3937Y0I3937J0D01*
G01X121260D01*
X127310Y11888D01*
G03X127953Y14567I-5263J2680D01*
G01Y17717D01*
G02X139764I5906J0D01*
G01Y14567D01*
G03X140406Y11888I5906J-1D01*
G01X146457Y0D01*
X1033465D01*
G03X1037402Y3937I0J3937D01*
G01Y1424882D01*
X1033465Y1428819D01*
X1028701D01*
G02X1023228Y1434291I0J5473D01*
G01Y1609902D01*
X1021260Y1611870D01*
X993681D01*
G02Y1616083I0J2107D01*
G01X1021260D01*
X1023228Y1618051D01*
G01X-7874Y39059D02*
G03X0I3937J0D01*
G01Y8350D02*
G03X-7874I-3937J0D01*
G01D02*
Y0D01*
G01Y251657D02*
Y39059D01*
G01X0Y251657D02*
G03X-7874I-3937J0D01*
G01Y282366D02*
G03X0I3937J0D01*
G01X-7874Y494965D02*
Y282366D01*
G01Y525673D02*
G03X0I3937J0D01*
G01Y494965D02*
G03X-7874I-3937J0D01*
G01Y534024D02*
Y525673D01*
G01X0Y993079D02*
G03X-7874I-3937J0D01*
G01Y986780D02*
Y993079D01*
G01Y1023787D02*
G03X0I3937J0D01*
G01X-7874D02*
Y1030087D01*
G01Y1930791D02*
Y1900165D01*
G01X0Y1930791D02*
G03X-7874I-3937J0D01*
G01Y1961500D02*
G03X0I3937J0D01*
G01X-7874Y1992126D02*
Y1961500D01*
G01X1045276Y0D02*
X1112953D01*
G03X1127953Y15000I0J15000D01*
G01Y493259D01*
G01X1045276Y25827D02*
G03X1037402I-3937J0D01*
G01X1045276Y0D02*
Y25827D01*
G01X1037402Y56535D02*
G03X1045276I3937J0D01*
G01D02*
Y284882D01*
G01X1037402Y315591D02*
G03X1045276I3937J0D01*
G01Y284882D02*
G03X1037402I-3937J0D01*
G01X1045276Y315591D02*
Y543937D01*
G01D02*
G03X1037402I-3937J0D01*
G01Y574646D02*
G03X1045276I3937J0D01*
G01D02*
Y802992D01*
G01X1037402Y833701D02*
G03X1045276I3937J0D01*
G01Y802992D02*
G03X1037402I-3937J0D01*
G01X1045276Y833701D02*
Y1062047D01*
G01D02*
G03X1037402I-3937J0D01*
G01Y1092756D02*
G03X1045276I3937J0D01*
G01D02*
Y1321102D01*
G01D02*
G03X1037402I-3937J0D01*
G01Y1351811D02*
G03X1045276I3937J0D01*
G01D02*
Y1377638D01*
G01D02*
X1112953D01*
G02X1127953Y1362638I0J-15000D01*
G01Y501133D01*
G01X1045276Y1732598D02*
X1112953D01*
G03X1127953Y1747598I0J15000D01*
G01Y1977126D01*
G03X1112953Y1992126I-15000J0D01*
G01X1045276D01*
G01X1037402Y1767835D02*
G03X1045276I3937J0D01*
G01Y1737126D02*
G03X1037402I-3937J0D01*
G01X1045276Y1767835D02*
Y1956890D01*
G01Y1732598D02*
Y1737126D01*
G01X1037402Y1987598D02*
G03X1045276I3937J0D01*
G01Y1956890D02*
G03X1037402I-3937J0D01*
G01X1045276Y1987598D02*
Y1992126D01*
G01X1127953Y501133D02*
G03Y493259I0J-3937D01*
G54D12*
G01X15376Y622420D02*
X19002D01*
G01X15376Y621219D02*
X18999D01*
G01X15376D02*
X18999D01*
G01X15376Y622420D02*
X19002D01*
G01X15376Y609821D02*
X19001D01*
G01X15376Y608620D02*
X19000D01*
G01X15376D02*
X19000D01*
G01X15376Y609821D02*
X19001D01*
G01X15376Y647616D02*
X19001D01*
G01X15376Y646415D02*
X19000D01*
G01X15376D02*
X19000D01*
G01X15376Y647616D02*
X19001D01*
G01X15376Y698010D02*
X19001D01*
G01X15376Y696809D02*
X19000D01*
G01X15376D02*
X19000D01*
G01X15376Y698010D02*
X19001D01*
G01X15376Y635018D02*
X19001D01*
G01X15376Y633817D02*
X19000D01*
G01X15376D02*
X19000D01*
G01X15376Y635018D02*
X19001D01*
G01X15376Y685412D02*
X19002D01*
G01X15376Y684211D02*
X18999D01*
G01X15376D02*
X18999D01*
G01X15376Y685412D02*
X19002D01*
G01X15376Y672813D02*
X19001D01*
G01X15376Y671612D02*
X19000D01*
G01X15376D02*
X19000D01*
G01X15376Y672813D02*
X19001D01*
G01X15376Y660215D02*
X19002D01*
G01X15376Y659014D02*
X18999D01*
G01X15376D02*
X18999D01*
G01X15376Y660215D02*
X19002D01*
G01X15376Y767301D02*
X19001D01*
G01X15376Y766100D02*
X19000D01*
G01X15376D02*
X19000D01*
G01X15376Y767301D02*
X19001D01*
G01X15376Y754703D02*
X19001D01*
G01X15376Y753502D02*
X19000D01*
G01X15376D02*
X19000D01*
G01X15376Y754703D02*
X19001D01*
G01X15376Y723207D02*
X19001D01*
G01X15376Y722006D02*
X19000D01*
G01X15376D02*
X19000D01*
G01X15376Y723207D02*
X19001D01*
G01X15376Y710608D02*
X19001D01*
G01X15376Y709407D02*
X19000D01*
G01X15376D02*
X19000D01*
G01X15376Y710608D02*
X19001D01*
G01X15376Y827144D02*
X19001D01*
G01X15376Y825943D02*
X19000D01*
G01X15376D02*
X19000D01*
G01X15376Y827144D02*
X19001D01*
G01X15376Y814546D02*
X19002D01*
G01X15376Y813345D02*
X18999D01*
G01X15376D02*
X18999D01*
G01X15376Y814546D02*
X19002D01*
G01X15376Y801947D02*
X19001D01*
G01X15376Y800746D02*
X19000D01*
G01X15376D02*
X19000D01*
G01X15376Y801947D02*
X19001D01*
G01X15376Y789349D02*
X19002D01*
G01X15376Y788148D02*
X18999D01*
G01X15376D02*
X18999D01*
G01X15376Y789349D02*
X19002D01*
G01X15718Y839742D02*
X19001D01*
G01X15770Y838541D02*
X19000D01*
G01X15770D02*
X19000D01*
G01X15718Y839742D02*
X19001D01*
G01X15376Y877538D02*
X19002D01*
G01X15376Y876337D02*
X18999D01*
G01X15376D02*
X18999D01*
G01X15376Y877538D02*
X19002D01*
G01X15851Y864939D02*
X19001D01*
G01X15801Y863738D02*
X19000D01*
G01X15801D02*
X19000D01*
G01X15851Y864939D02*
X19001D01*
G01X15376Y915333D02*
X19001D01*
G01X15376Y914132D02*
X19000D01*
G01X15376D02*
X19000D01*
G01X15376Y915333D02*
X19001D01*
G01X15869Y852341D02*
X19002D01*
G01X15880Y851140D02*
X18999D01*
G01X15880D02*
X18999D01*
G01X15869Y852341D02*
X19002D01*
G01X15376Y902734D02*
X19001D01*
G01X15376Y901533D02*
X19000D01*
G01X15376D02*
X19000D01*
G01X15376Y902734D02*
X19001D01*
G01X15376Y1118483D02*
X19002D01*
G01X15376Y1117282D02*
X18999D01*
G01X15376D02*
X18999D01*
G01X15376Y1118483D02*
X19002D01*
G01X15376Y1105884D02*
X19001D01*
G01X15376Y1104683D02*
X19000D01*
G01X15376D02*
X19000D01*
G01X15376Y1105884D02*
X19001D01*
G01X15376Y1181475D02*
X19002D01*
G01X15376Y1180274D02*
X18999D01*
G01X15376D02*
X18999D01*
G01X15376Y1181475D02*
X19002D01*
G01X15376Y1168876D02*
X19001D01*
G01X15376Y1167675D02*
X19000D01*
G01X15376D02*
X19000D01*
G01X15376Y1168876D02*
X19001D01*
G01X15376Y1206671D02*
X19001D01*
G01X15376Y1205470D02*
X19000D01*
G01X15376D02*
X19000D01*
G01X15376Y1206671D02*
X19001D01*
G01X15376Y1156278D02*
X19002D01*
G01X15376Y1155077D02*
X18999D01*
G01X15376D02*
X18999D01*
G01X15376Y1156278D02*
X19002D01*
G01X15376Y1194073D02*
X19001D01*
G01X15376Y1192872D02*
X19000D01*
G01X15376D02*
X19000D01*
G01X15376Y1194073D02*
X19001D01*
G01X15376Y1143679D02*
X19001D01*
G01X15376Y1142478D02*
X19000D01*
G01X15376D02*
X19000D01*
G01X15376Y1143679D02*
X19001D01*
G01X15376Y1250766D02*
X19001D01*
G01X15376Y1249565D02*
X19000D01*
G01X15376D02*
X19000D01*
G01X15376Y1250766D02*
X19001D01*
G01X15376Y1219270D02*
X19001D01*
G01X15376Y1218069D02*
X19000D01*
G01X15376D02*
X19000D01*
G01X15376Y1219270D02*
X19001D01*
G01X15376Y1275963D02*
X19002D01*
G01X15376Y1274762D02*
X18999D01*
G01X15376D02*
X18999D01*
G01X15376Y1275963D02*
X19002D01*
G01X15376Y1263364D02*
X19001D01*
G01X15376Y1262163D02*
X19000D01*
G01X15376D02*
X19000D01*
G01X15376Y1263364D02*
X19001D01*
G01X15376Y1301160D02*
X19002D01*
G01X15376Y1299959D02*
X18999D01*
G01X15376D02*
X18999D01*
G01X15376Y1301160D02*
X19002D01*
G01X15376Y1288561D02*
X19001D01*
G01X15376Y1287360D02*
X19000D01*
G01X15376D02*
X19000D01*
G01X15376Y1288561D02*
X19001D01*
G01X15790Y1348404D02*
X19002D01*
G01X15376Y1347203D02*
X18999D01*
G01X15376D02*
X18999D01*
G01X15790Y1348404D02*
X19002D01*
G01X15376Y1335805D02*
X19001D01*
G01X15376Y1334604D02*
X19000D01*
G01X15376D02*
X19000D01*
G01X15376Y1335805D02*
X19001D01*
G01X15376Y1323207D02*
X19001D01*
G01X15376Y1322006D02*
X19000D01*
G01X15376D02*
X19000D01*
G01X15376Y1323207D02*
X19001D01*
G01X15376Y1411396D02*
X19001D01*
G01X15376Y1410195D02*
X19000D01*
G01X15376D02*
X19000D01*
G01X15376Y1411396D02*
X19001D01*
G01X15770Y1361002D02*
X19001D01*
G01X15351Y1359801D02*
X19000D01*
G01X15351D02*
X19000D01*
G01X15770Y1361002D02*
X19001D01*
G01X15376Y1398797D02*
X19001D01*
G01X15376Y1397596D02*
X19000D01*
G01X15376D02*
X19000D01*
G01X15376Y1398797D02*
X19001D01*
G01X15376Y1386199D02*
X19001D01*
G01X15376Y1384998D02*
X19000D01*
G01X15376D02*
X19000D01*
G01X15376Y1386199D02*
X19001D01*
G01X15376Y1373601D02*
X19002D01*
G01X15376Y1372400D02*
X18999D01*
G01X15376D02*
X18999D01*
G01X15376Y1373601D02*
X19002D01*
G01X18908Y1514892D02*
X15153D01*
G01X19406Y1516093D02*
X15439D01*
G01X21001Y1512799D02*
X18908Y1514892D01*
G01X21499Y1514000D02*
X19406Y1516093D01*
G01X33915Y1512799D02*
X21001D01*
G01X23564Y1514000D02*
X21499D01*
G01X28698D02*
X26634D01*
G01X33417D02*
X31768D01*
G01X35201Y1514085D02*
X33915Y1512799D01*
G01X34000Y1514583D02*
X33417Y1514000D01*
G01X35201Y1517123D02*
Y1514085D01*
G01X34000Y1517124D02*
Y1514583D01*
G01X19406Y1516093D02*
X15439D01*
G01X18908Y1514892D02*
X15153D01*
G01X21499Y1514000D02*
X19406Y1516093D01*
G01X21001Y1512799D02*
X18908Y1514892D01*
G01X23564Y1514000D02*
X21499D01*
G01X33915Y1512799D02*
X21001D01*
G01X28698Y1514000D02*
X26634D01*
G01X33915Y1512799D02*
X21001D01*
G01X33417Y1514000D02*
X31768D01*
G01X33915Y1512799D02*
X21001D01*
G01X34000Y1514583D02*
X33417Y1514000D01*
G01X35201Y1514085D02*
X33915Y1512799D01*
G01X34000Y1517124D02*
Y1514583D01*
G01X35201Y1517123D02*
Y1514085D01*
G01X15376Y1570450D02*
X19001D01*
G01X15376Y1569249D02*
X19000D01*
G01X15376D02*
X19000D01*
G01X15376Y1570450D02*
X19001D01*
G01X15375Y1557852D02*
X19002D01*
G01X15375Y1556651D02*
X18999D01*
G01X15375D02*
X18999D01*
G01X15375Y1557852D02*
X19002D01*
G01X15376Y1545253D02*
X19001D01*
G01X15376Y1544052D02*
X19000D01*
G01X15376D02*
X19000D01*
G01X15376Y1545253D02*
X19001D01*
G01X15376Y1532655D02*
X19001D01*
G01X15376Y1531454D02*
X19000D01*
G01X15376D02*
X19000D01*
G01X15376Y1532655D02*
X19001D01*
G01X15375Y1629092D02*
X18999D01*
G01X15375Y1630293D02*
X19002D01*
G01X15375D02*
X19002D01*
G01X15375Y1629092D02*
X18999D01*
G01X15376Y1616493D02*
X19000D01*
G01X15376Y1617694D02*
X19001D01*
G01X15376D02*
X19001D01*
G01X15376Y1616493D02*
X19000D01*
G01X15375Y1603895D02*
X18999D01*
G01X15375Y1605096D02*
X19002D01*
G01X15375D02*
X19002D01*
G01X15375Y1603895D02*
X18999D01*
G01X15376Y1591296D02*
X19000D01*
G01X15376Y1592497D02*
X19001D01*
G01X15376D02*
X19001D01*
G01X15376Y1591296D02*
X19000D01*
G01X15376Y1642891D02*
X19001D01*
G01X15376Y1641690D02*
X19000D01*
G01X15376D02*
X19000D01*
G01X15376Y1642891D02*
X19001D01*
G01X15375Y1693285D02*
X19002D01*
G01X15375Y1692084D02*
X18999D01*
G01X15375D02*
X18999D01*
G01X15375Y1693285D02*
X19002D01*
G01X15376Y1680687D02*
X19002D01*
G01X15376Y1679486D02*
X18999D01*
G01X15376D02*
X18999D01*
G01X15376Y1680687D02*
X19002D01*
G01X15376Y1668089D02*
X19002D01*
G01X15376Y1666888D02*
X18999D01*
G01X15376D02*
X18999D01*
G01X15376Y1668089D02*
X19002D01*
G01X15376Y1714132D02*
X18999D01*
G01X15376Y1715333D02*
X19002D01*
G01X15376D02*
X19002D01*
G01X15376Y1714132D02*
X18999D01*
G01X27701Y1766002D02*
Y1768559D01*
G01X26500Y1766500D02*
Y1768558D01*
G01X25998Y1764299D02*
X27701Y1766002D01*
G01X25500Y1765500D02*
X26500Y1766500D01*
G01X22299Y1764299D02*
X25998D01*
G01X21801Y1765500D02*
X25500D01*
G01X19375Y1761375D02*
X22299Y1764299D01*
G01X18877Y1762576D02*
X21801Y1765500D01*
G01X15376Y1761375D02*
X19375D01*
G01X15376Y1762576D02*
X18877D01*
G01X26500Y1766500D02*
Y1768558D01*
G01X27701Y1766002D02*
Y1768559D01*
G01X25500Y1765500D02*
X26500Y1766500D01*
G01X25998Y1764299D02*
X27701Y1766002D01*
G01X21801Y1765500D02*
X25500D01*
G01X22299Y1764299D02*
X25998D01*
G01X18877Y1762576D02*
X21801Y1765500D01*
G01X19375Y1761375D02*
X22299Y1764299D01*
G01X15376Y1762576D02*
X18877D01*
G01X15376Y1761375D02*
X19375D01*
G01X15375Y1751925D02*
X19001D01*
G01X15377Y1753126D02*
X19000D01*
G01X15377D02*
X19000D01*
G01X15375Y1751925D02*
X19001D01*
G01X15376Y1739329D02*
X18999D01*
G01X15376Y1740530D02*
X19002D01*
G01X15376D02*
X19002D01*
G01X15376Y1739329D02*
X18999D01*
G01X15375Y1726730D02*
X18999D01*
G01X15375Y1727931D02*
X19002D01*
G01X15375D02*
X19002D01*
G01X15375Y1726730D02*
X18999D01*
G01X69000Y130559D02*
X123000D01*
G01X68999Y129358D02*
X123001D01*
G01X68999D02*
X123001D01*
G01X69000Y130559D02*
X123000D01*
G01Y536073D02*
X68998D01*
G01X69001Y534872D02*
X123001D01*
G01X69001D02*
X123001D01*
G01X123000Y536073D02*
X68998D01*
G01X69074Y941509D02*
X166000D01*
G01X110562Y940308D02*
X68925D01*
G01X110562D02*
X68925D01*
G01X69074Y941509D02*
X166000D01*
G01X69074D02*
X166000D01*
G01X69074D02*
X166000D01*
G01X69074D02*
X166000D01*
G01X69074D02*
X166000D01*
G01X69074D02*
X166000D01*
G01X69074Y1347021D02*
X128500D01*
G01X68925Y1345820D02*
X128501D01*
G01X68925D02*
X128501D01*
G01X69074Y1347021D02*
X128500D01*
G01X69073Y1752534D02*
X124000D01*
G01X68926Y1751333D02*
X124001D01*
G01X68926D02*
X124001D01*
G01X69073Y1752534D02*
X124000D01*
G01X177799Y238998D02*
Y236393D01*
G01X179000Y238500D02*
Y236394D01*
G01X179502Y240701D02*
X177799Y238998D01*
G01X180000Y239500D02*
X179000Y238500D01*
G01X189500Y240701D02*
X179502D01*
G01X189501Y239500D02*
X180000D01*
G01X179000Y238500D02*
Y236394D01*
G01X177799Y238998D02*
Y236393D01*
G01X180000Y239500D02*
X179000Y238500D01*
G01X179502Y240701D02*
X177799Y238998D01*
G01X189501Y239500D02*
X180000D01*
G01X189500Y240701D02*
X179502D01*
G01X177799Y644510D02*
Y641905D01*
G01X179000Y644012D02*
Y641906D01*
G01X179502Y646213D02*
X177799Y644510D01*
G01X180000Y645012D02*
X179000Y644012D01*
G01X189500Y646213D02*
X179502D01*
G01X189501Y645012D02*
X180000D01*
G01X179000Y644012D02*
Y641906D01*
G01X177799Y644510D02*
Y641905D01*
G01X180000Y645012D02*
X179000Y644012D01*
G01X179502Y646213D02*
X177799Y644510D01*
G01X189501Y645012D02*
X180000D01*
G01X189500Y646213D02*
X179502D01*
G01X115696Y940308D02*
X113632D01*
G01X120830D02*
X118766D01*
G01X133900D02*
X123900D01*
G01X139034D02*
X136970D01*
G01X166001D02*
X142104D01*
G01X115696D02*
X113632D01*
G01X120830D02*
X118766D01*
G01X133900D02*
X123900D01*
G01X139034D02*
X136970D01*
G01X166001D02*
X142104D01*
G01X179502Y1051725D02*
X189500D01*
G01X180000Y1050524D02*
X189501D01*
G01X177799Y1050022D02*
X179502Y1051725D01*
G01X179000Y1049524D02*
X180000Y1050524D01*
G01X177799Y1047417D02*
Y1050022D01*
G01X179000Y1047418D02*
Y1049524D01*
G01X180000Y1050524D02*
X189501D01*
G01X179502Y1051725D02*
X189500D01*
G01X179000Y1049524D02*
X180000Y1050524D01*
G01X177799Y1050022D02*
X179502Y1051725D01*
G01X179000Y1047418D02*
Y1049524D01*
G01X177799Y1047417D02*
Y1050022D01*
G01Y1455534D02*
Y1452929D01*
G01X179000Y1455036D02*
Y1452930D01*
G01X179502Y1457237D02*
X177799Y1455534D01*
G01X180000Y1456036D02*
X179000Y1455036D01*
G01X189500Y1457237D02*
X179502D01*
G01X189501Y1456036D02*
X180000D01*
G01X179000Y1455036D02*
Y1452930D01*
G01X177799Y1455534D02*
Y1452929D01*
G01X180000Y1456036D02*
X179000Y1455036D01*
G01X179502Y1457237D02*
X177799Y1455534D01*
G01X189501Y1456036D02*
X180000D01*
G01X189500Y1457237D02*
X179502D01*
G01Y1862749D02*
X189500D01*
G01X180000Y1861548D02*
X189501D01*
G01X177799Y1861046D02*
X179502Y1862749D01*
G01X179000Y1860548D02*
X180000Y1861548D01*
G01X177799Y1858441D02*
Y1861046D01*
G01X179000Y1858442D02*
Y1860548D01*
G01X180000Y1861548D02*
X189501D01*
G01X179502Y1862749D02*
X189500D01*
G01X179000Y1860548D02*
X180000Y1861548D01*
G01X177799Y1861046D02*
X179502Y1862749D01*
G01X179000Y1858442D02*
Y1860548D01*
G01X177799Y1858441D02*
Y1861046D01*
G01X292002Y1698399D02*
X285999D01*
G01X292500Y1699600D02*
X286000D01*
G01X293399Y1697002D02*
X292002Y1698399D01*
G01X294600Y1697500D02*
X292500Y1699600D01*
G01X293399Y1694399D02*
Y1697002D01*
G01X294600Y1694400D02*
Y1697500D01*
G01X292500Y1699600D02*
X286000D01*
G01X292002Y1698399D02*
X285999D01*
G01X294600Y1697500D02*
X292500Y1699600D01*
G01X293399Y1697002D02*
X292002Y1698399D01*
G01X294600Y1694400D02*
Y1697500D01*
G01X293399Y1694399D02*
Y1697002D01*
G01X907848Y240701D02*
X917846D01*
G01X908346Y239500D02*
X917847D01*
G01X906145Y238998D02*
X907848Y240701D01*
G01X907346Y238500D02*
X908346Y239500D01*
G01X906145Y236393D02*
Y238998D01*
G01X907346Y236394D02*
Y238500D01*
G01X908346Y239500D02*
X917847D01*
G01X907848Y240701D02*
X917846D01*
G01X907346Y238500D02*
X908346Y239500D01*
G01X906145Y238998D02*
X907848Y240701D01*
G01X907346Y236394D02*
Y238500D01*
G01X906145Y236393D02*
Y238998D01*
G01Y644510D02*
Y641905D01*
G01X907346Y644012D02*
Y641906D01*
G01X907848Y646213D02*
X906145Y644510D01*
G01X908346Y645012D02*
X907346Y644012D01*
G01X917846Y646213D02*
X907848D01*
G01X917847Y645012D02*
X908346D01*
G01X907346Y644012D02*
Y641906D01*
G01X906145Y644510D02*
Y641905D01*
G01X908346Y645012D02*
X907346Y644012D01*
G01X907848Y646213D02*
X906145Y644510D01*
G01X917847Y645012D02*
X908346D01*
G01X917846Y646213D02*
X907848D01*
G01X906145Y1050022D02*
Y1047417D01*
G01X907346Y1049524D02*
Y1047418D01*
G01X907848Y1051725D02*
X906145Y1050022D01*
G01X908346Y1050524D02*
X907346Y1049524D01*
G01X917846Y1051725D02*
X907848D01*
G01X917847Y1050524D02*
X908346D01*
G01X907346Y1049524D02*
Y1047418D01*
G01X906145Y1050022D02*
Y1047417D01*
G01X908346Y1050524D02*
X907346Y1049524D01*
G01X907848Y1051725D02*
X906145Y1050022D01*
G01X917847Y1050524D02*
X908346D01*
G01X917846Y1051725D02*
X907848D01*
G01X906145Y1455534D02*
Y1452929D01*
G01X907346Y1455036D02*
Y1452930D01*
G01X907848Y1457237D02*
X906145Y1455534D01*
G01X908346Y1456036D02*
X907346Y1455036D01*
G01X917846Y1457237D02*
X907848D01*
G01X917847Y1456036D02*
X908346D01*
G01X907346Y1455036D02*
Y1452930D01*
G01X906145Y1455534D02*
Y1452929D01*
G01X908346Y1456036D02*
X907346Y1455036D01*
G01X907848Y1457237D02*
X906145Y1455534D01*
G01X917847Y1456036D02*
X908346D01*
G01X917846Y1457237D02*
X907848D01*
G01X906145Y1861046D02*
Y1858441D01*
G01X907346Y1860548D02*
Y1858442D01*
G01X907848Y1862749D02*
X906145Y1861046D01*
G01X908346Y1861548D02*
X907346Y1860548D01*
G01X917846Y1862749D02*
X907848D01*
G01X917847Y1861548D02*
X908346D01*
G01X907346Y1860548D02*
Y1858442D01*
G01X906145Y1861046D02*
Y1858441D01*
G01X908346Y1861548D02*
X907346Y1860548D01*
G01X907848Y1862749D02*
X906145Y1861046D01*
G01X917847Y1861548D02*
X908346D01*
G01X917846Y1862749D02*
X907848D01*
M02*
